# T6G (Grand Teton) — schematic netlist excerpt (pin names and nets, part order shuffled) for the footprints in the layout excerpt that follows; sources: Cadence DE-HDL packaged netlist, KiCad conversion of 04192023_DAF0TMB3IC0_F0TG_MB_C_brd_V02_OCP.brd

R182  Q_RES  0 5% CHIP  pkg 0402LF  page 82 : A = FM_PRSNT_CPU0_R_N ; B = FM_PRSNT_CPU0_N
PR438  Q_RES  49.9 1% CHIP  pkg 0402LF  page 209 : A = PVDD18_S5_P0_FB_RC ; B = PVDD18_S5_P0

(kicad_pcb
	(version 20260206)
	(generator "pcbnew")
	(generator_version "10.0")
	(general
		(thickness 1.6)
		(legacy_teardrops no)
	)
	(paper "A4")
	(title_block
		(title "04192023_DAF0TMB3IC0_F0TG_MB_C_brd_V02_OCP.brd")
		(comment 1 "Grand Teton / footprints 4455-4456 of 8354")
	)
	(layers
		(0 "F.Cu" signal "TOP")
		(4 "In1.Cu" signal "GND")
		(6 "In2.Cu" signal "IN1")
		(8 "In3.Cu" signal "GND1")
		(10 "In4.Cu" signal "IN2")
		(12 "In5.Cu" signal "GND2")
		(14 "In6.Cu" signal "IN3")
		(16 "In7.Cu" signal "GND3")
		(18 "In8.Cu" signal "VCC")
		(20 "In9.Cu" signal "VCC1")
		(22 "In10.Cu" signal "GND4")
		(24 "In11.Cu" signal "IN4")
		(26 "In12.Cu" signal "GND5")
		(28 "In13.Cu" signal "IN5")
		(30 "In14.Cu" signal "GND6")
		(32 "In15.Cu" signal "IN6")
		(34 "In16.Cu" signal "GND7")
		(2 "B.Cu" signal "BOTTOM")
		(9 "F.Adhes" user "F.Adhesive")
		(11 "B.Adhes" user "B.Adhesive")
		(13 "F.Paste" user "Package Geometry/Pastemask Top")
		(15 "B.Paste" user "Package Geometry/Pastemask Bottom")
		(5 "F.SilkS" user "Ref Des/Silkscreen Top")
		(7 "B.SilkS" user "Ref Des/Silkscreen Bottom")
		(1 "F.Mask" user "Board Geometry/Soldermask Top")
		(3 "B.Mask" user "Board Geometry/Soldermask Bottom")
		(17 "Dwgs.User" user "User.Drawings")
		(19 "Cmts.User" user "User.Comments")
		(21 "Eco1.User" user "User.Eco1")
		(23 "Eco2.User" user "User.Eco2")
		(25 "Edge.Cuts" user "Board Geometry/Outline")
		(27 "Margin" user)
		(31 "F.CrtYd" user "Package Geometry/Place Bound Top")
		(29 "B.CrtYd" user "Package Geometry/Place Bound Bottom")
		(35 "F.Fab" user "Ref Des/Assembly Top")
		(33 "B.Fab" user "Ref Des/Assembly Bottom")
	)
	(footprint ""
		(layer "F.Cu")
		(at 194.945 -100.294948 -90)
		(property "Reference" "R182"
			(at 0 0 270)
			(layer "F.SilkS")
			(hide yes)
			(effects
				(font
					(size 1.27 1.27)
				)
			)
		)
		(property "Value" ""
			(at 0 0 270)
			(layer "F.Fab")
			(effects
				(font
					(size 1.27 1.27)
				)
			)
		)
		(duplicate_pad_numbers_are_jumpers no)
		(fp_line
			(start -0.7874 0.4064)
			(end -0.7874 -0.4064)
			(stroke
				(width 0.1524)
				(type default)
			)
			(layer "F.SilkS")
		)
		(fp_line
			(start 0.7874 0.4064)
			(end -0.7874 0.4064)
			(stroke
				(width 0.1524)
				(type default)
			)
			(layer "F.SilkS")
		)
		(fp_line
			(start -0.7874 -0.4064)
			(end 0.7874 -0.4064)
			(stroke
				(width 0.1524)
				(type default)
			)
			(layer "F.SilkS")
		)
		(fp_line
			(start 0.7874 -0.4064)
			(end 0.7874 0.4064)
			(stroke
				(width 0.1524)
				(type default)
			)
			(layer "F.SilkS")
		)
		(fp_line
			(start -0.67945 0.3048)
			(end -0.67945 -0.305054)
			(stroke
				(width 0.1)
				(type default)
			)
			(layer "F.Fab")
		)
		(fp_line
			(start -0.12065 0.3048)
			(end -0.67945 0.3048)
			(stroke
				(width 0.1)
				(type default)
			)
			(layer "F.Fab")
		)
		(fp_line
			(start 0.120396 0.3048)
			(end 0.120396 0.2794)
			(stroke
				(width 0.1)
				(type default)
			)
			(layer "F.Fab")
		)
		(fp_line
			(start 0.67945 0.3048)
			(end 0.120396 0.3048)
			(stroke
				(width 0.1)
				(type default)
			)
			(layer "F.Fab")
		)
		(fp_line
			(start -0.12065 0.2794)
			(end -0.12065 0.3048)
			(stroke
				(width 0.1)
				(type default)
			)
			(layer "F.Fab")
		)
		(fp_line
			(start 0.120396 0.2794)
			(end -0.12065 0.2794)
			(stroke
				(width 0.1)
				(type default)
			)
			(layer "F.Fab")
		)
		(fp_line
			(start -0.12065 -0.2794)
			(end 0.12065 -0.2794)
			(stroke
				(width 0.1)
				(type default)
			)
			(layer "F.Fab")
		)
		(fp_line
			(start 0.12065 -0.2794)
			(end 0.12065 -0.3048)
			(stroke
				(width 0.1)
				(type default)
			)
			(layer "F.Fab")
		)
		(fp_line
			(start 0.12065 -0.3048)
			(end 0.67945 -0.3048)
			(stroke
				(width 0.1)
				(type default)
			)
			(layer "F.Fab")
		)
		(fp_line
			(start 0.67945 -0.3048)
			(end 0.67945 0.3048)
			(stroke
				(width 0.1)
				(type default)
			)
			(layer "F.Fab")
		)
		(fp_line
			(start -0.67945 -0.305054)
			(end -0.12065 -0.305054)
			(stroke
				(width 0.1)
				(type default)
			)
			(layer "F.Fab")
		)
		(fp_line
			(start -0.12065 -0.305054)
			(end -0.12065 -0.2794)
			(stroke
				(width 0.1)
				(type default)
			)
			(layer "F.Fab")
		)
		(pad "1" smd circle
			(at -0.40005 0 270)
			(size 0 0)
			(layers "F.Cu" "F.Mask" "F.Paste")
			(net "FM_PRSNT_CPU0_R_N")
		)
		(pad "2" smd circle
			(at 0.40005 0 270)
			(size 0 0)
			(layers "F.Cu" "F.Mask" "F.Paste")
			(net "FM_PRSNT_CPU0_N")
		)
	)
	(footprint ""
		(layer "F.Cu")
		(at 328.514964 -151.641302)
		(property "Reference" "PR438"
			(at 0 0 0)
			(layer "F.SilkS")
			(hide yes)
			(effects
				(font
					(size 1.27 1.27)
				)
			)
		)
		(property "Value" ""
			(at 0 0 0)
			(layer "F.Fab")
			(effects
				(font
					(size 1.27 1.27)
				)
			)
		)
		(duplicate_pad_numbers_are_jumpers no)
		(fp_line
			(start -0.7874 -0.4064)
			(end 0.7874 -0.4064)
			(stroke
				(width 0.1524)
				(type default)
			)
			(layer "F.SilkS")
		)
		(fp_line
			(start -0.7874 0.4064)
			(end -0.7874 -0.4064)
			(stroke
				(width 0.1524)
				(type default)
			)
			(layer "F.SilkS")
		)
		(fp_line
			(start 0.7874 -0.4064)
			(end 0.7874 0.4064)
			(stroke
				(width 0.1524)
				(type default)
			)
			(layer "F.SilkS")
		)
		(fp_line
			(start 0.7874 0.4064)
			(end -0.7874 0.4064)
			(stroke
				(width 0.1524)
				(type default)
			)
			(layer "F.SilkS")
		)
		(fp_line
			(start -0.67945 -0.305054)
			(end -0.12065 -0.305054)
			(stroke
				(width 0.1)
				(type default)
			)
			(layer "F.Fab")
		)
		(fp_line
			(start -0.67945 0.3048)
			(end -0.67945 -0.305054)
			(stroke
				(width 0.1)
				(type default)
			)
			(layer "F.Fab")
		)
		(fp_line
			(start -0.12065 -0.305054)
			(end -0.12065 -0.2794)
			(stroke
				(width 0.1)
				(type default)
			)
			(layer "F.Fab")
		)
		(fp_line
			(start -0.12065 -0.2794)
			(end 0.12065 -0.2794)
			(stroke
				(width 0.1)
				(type default)
			)
			(layer "F.Fab")
		)
		(fp_line
			(start -0.12065 0.2794)
			(end -0.12065 0.3048)
			(stroke
				(width 0.1)
				(type default)
			)
			(layer "F.Fab")
		)
		(fp_line
			(start -0.12065 0.3048)
			(end -0.67945 0.3048)
			(stroke
				(width 0.1)
				(type default)
			)
			(layer "F.Fab")
		)
		(fp_line
			(start 0.120396 0.2794)
			(end -0.12065 0.2794)
			(stroke
				(width 0.1)
				(type default)
			)
			(layer "F.Fab")
		)
		(fp_line
			(start 0.120396 0.3048)
			(end 0.120396 0.2794)
			(stroke
				(width 0.1)
				(type default)
			)
			(layer "F.Fab")
		)
		(fp_line
			(start 0.12065 -0.3048)
			(end 0.67945 -0.3048)
			(stroke
				(width 0.1)
				(type default)
			)
			(layer "F.Fab")
		)
		(fp_line
			(start 0.12065 -0.2794)
			(end 0.12065 -0.3048)
			(stroke
				(width 0.1)
				(type default)
			)
			(layer "F.Fab")
		)
		(fp_line
			(start 0.67945 -0.3048)
			(end 0.67945 0.3048)
			(stroke
				(width 0.1)
				(type default)
			)
			(layer "F.Fab")
		)
		(fp_line
			(start 0.67945 0.3048)
			(end 0.120396 0.3048)
			(stroke
				(width 0.1)
				(type default)
			)
			(layer "F.Fab")
		)
		(pad "1" smd circle
			(at -0.40005 0)
			(size 0 0)
			(layers "F.Cu" "F.Mask" "F.Paste")
			(net "PVDD18_S5_P0_FB_RC")
		)
		(pad "2" smd circle
			(at 0.40005 0)
			(size 0 0)
			(layers "F.Cu" "F.Mask" "F.Paste")
			(net "PVDD18_S5_P0")
		)
	)
)
